(kicad_pcb
	(version 20241229)
	(generator "pcbnew")
	(generator_version "9.0")
	(general
		(thickness 1.62)
		(legacy_teardrops no)
	)
	(paper "A3")
	(title_block
		(title "COM Express 7 Baseboard")
		(date "2025-02-04")
		(rev "1.1.2")
		(company "Antmicro Ltd")
		(comment 1 "www.antmicro.com")
		(comment 9 "footprints 165-169 of 802")
	)
	(layers
		(0 "F.Cu" signal)
		(4 "In1.Cu" signal)
		(6 "In2.Cu" signal)
		(8 "In3.Cu" signal)
		(10 "In4.Cu" signal)
		(12 "In5.Cu" signal)
		(14 "In6.Cu" signal)
		(2 "B.Cu" signal)
		(9 "F.Adhes" user "F.Adhesive")
		(11 "B.Adhes" user "B.Adhesive")
		(13 "F.Paste" user)
		(15 "B.Paste" user)
		(5 "F.SilkS" user "F.Silkscreen")
		(7 "B.SilkS" user "B.Silkscreen")
		(1 "F.Mask" user)
		(3 "B.Mask" user)
		(17 "Dwgs.User" user "User.Drawings")
		(19 "Cmts.User" user "User.Comments")
		(21 "Eco1.User" user "User.Eco1")
		(23 "Eco2.User" user "User.Eco2")
		(25 "Edge.Cuts" user)
		(27 "Margin" user)
		(31 "F.CrtYd" user "F.Courtyard")
		(29 "B.CrtYd" user "B.Courtyard")
		(35 "F.Fab" user)
		(33 "B.Fab" user)
	)
	(footprint "antmicro-footprints:R_0402_1005Metric"
		(layer "F.Cu")
		(at 122.049999 85.06 180)
		(descr "Resistor SMD 0402")
		(tags "resistor SMD 0402")
		(property "Reference" "R27"
			(at -2.950001 -0.4 0)
			(layer "F.SilkS")
			(effects
				(font
					(size 0.7 0.7)
					(thickness 0.15)
				)
				(justify right bottom)
			)
		)
		(property "Value" "R_0R_0402"
			(at -1.011843 1.772047 0)
			(layer "F.Fab")
			(effects
				(font
					(size 0.7 0.7)
					(thickness 0.15)
				)
				(justify right bottom)
			)
		)
		(property "Datasheet" "https://industrial.panasonic.com/cdbs/www-data/pdf/RDA0000/AOA0000C301.pdf"
			(at 0 0 180)
			(layer "F.Fab")
			(hide yes)
			(effects
				(font
					(size 1.27 1.27)
					(thickness 0.15)
				)
			)
		)
		(property "Author" "Antmicro"
			(at 244.099998 170.12 0)
			(layer "F.Fab")
			(hide yes)
			(effects
				(font
					(size 1 1)
					(thickness 0.15)
				)
			)
		)
		(property "Current" "1A"
			(at 244.099998 170.12 0)
			(layer "F.Fab")
			(hide yes)
			(effects
				(font
					(size 1 1)
					(thickness 0.15)
				)
			)
		)
		(property "License" "Apache-2.0"
			(at 244.099998 170.12 0)
			(layer "F.Fab")
			(hide yes)
			(effects
				(font
					(size 1 1)
					(thickness 0.15)
				)
			)
		)
		(property "MPN" "ERJ2GE0R00X"
			(at 244.099998 170.12 0)
			(layer "F.Fab")
			(hide yes)
			(effects
				(font
					(size 1 1)
					(thickness 0.15)
				)
			)
		)
		(property "Manufacturer" "Panasonic"
			(at 244.099998 170.12 0)
			(layer "F.Fab")
			(hide yes)
			(effects
				(font
					(size 1 1)
					(thickness 0.15)
				)
			)
		)
		(property "Public" "False"
			(at 244.099998 170.12 0)
			(layer "F.Fab")
			(hide yes)
			(effects
				(font
					(size 1 1)
					(thickness 0.15)
				)
			)
		)
		(property "Tolerance" ""
			(at 244.099998 170.12 0)
			(layer "F.Fab")
			(hide yes)
			(effects
				(font
					(size 1 1)
					(thickness 0.15)
				)
			)
		)
		(property "Val" "0R"
			(at 244.099998 170.12 0)
			(layer "F.Fab")
			(hide yes)
			(effects
				(font
					(size 1 1)
					(thickness 0.15)
				)
			)
		)
		(sheetname "2xUSB3.0+RJ45")
		(sheetfile "usb3+rj45.kicad_sch")
		(attr smd)
		(fp_rect
			(start -0.925 -0.47)
			(end 0.925 0.47)
			(stroke
				(width 0.05)
				(type default)
			)
			(fill no)
			(layer "F.CrtYd")
		)
		(fp_rect
			(start -0.5 -0.25)
			(end 0.5 0.25)
			(stroke
				(width 0.15)
				(type solid)
			)
			(fill no)
			(layer "F.Fab")
		)
		(pad "1" smd roundrect
			(at -0.48 0 180)
			(size 0.59 0.64)
			(layers "F.Cu" "F.Mask" "F.Paste")
			(roundrect_rratio 0.25)
			(net 941 "/2xUSB3.0+RJ45/EN_1")
			(pintype "passive")
			(teardrops
				(best_length_ratio 0.2)
				(max_length 1)
				(best_width_ratio 0.9)
				(max_width 2)
				(curved_edges yes)
				(filter_ratio 0.9)
				(enabled yes)
				(allow_two_segments yes)
				(prefer_zone_connections yes)
			)
		)
		(pad "2" smd roundrect
			(at 0.48 0 180)
			(size 0.59 0.64)
			(layers "F.Cu" "F.Mask" "F.Paste")
			(roundrect_rratio 0.25)
			(net 555 "/2xUSB3.0+RJ45/EN_1B")
			(pintype "passive")
			(teardrops
				(best_length_ratio 0.2)
				(max_length 1)
				(best_width_ratio 0.9)
				(max_width 2)
				(curved_edges yes)
				(filter_ratio 0.9)
				(enabled yes)
				(allow_two_segments yes)
				(prefer_zone_connections yes)
			)
		)
	)
	(footprint "antmicro-footprints:C_0402_1005Metric"
		(layer "F.Cu")
		(at 310.075 77.862002 90)
		(descr "Capacitor SMD 0402")
		(tags "capacitor SMD 0402")
		(property "Reference" "C109"
			(at -1.797998 1.375 90)
			(layer "F.SilkS")
			(effects
				(font
					(size 0.7 0.7)
					(thickness 0.15)
				)
				(justify left bottom)
			)
		)
		(property "Value" "C_100n_0402"
			(at -1.022927 2.155213 90)
			(layer "F.Fab")
			(effects
				(font
					(size 0.7 0.7)
					(thickness 0.15)
				)
				(justify left bottom)
			)
		)
		(property "Datasheet" "https://www.murata.com/products/productdetail?partno=GRM155R61H104KE14%23"
			(at 0 0 90)
			(layer "F.Fab")
			(hide yes)
			(effects
				(font
					(size 1.27 1.27)
					(thickness 0.15)
				)
			)
		)
		(property "Author" "Antmicro"
			(at 387.937002 -232.212998 0)
			(layer "F.Fab")
			(hide yes)
			(effects
				(font
					(size 1 1)
					(thickness 0.15)
				)
			)
		)
		(property "Dielectric" "X5R"
			(at 387.937002 -232.212998 0)
			(layer "F.Fab")
			(hide yes)
			(effects
				(font
					(size 1 1)
					(thickness 0.15)
				)
			)
		)
		(property "License" "Apache-2.0"
			(at 387.937002 -232.212998 0)
			(layer "F.Fab")
			(hide yes)
			(effects
				(font
					(size 1 1)
					(thickness 0.15)
				)
			)
		)
		(property "MPN" "GRM155R61H104KE14D"
			(at 387.937002 -232.212998 0)
			(layer "F.Fab")
			(hide yes)
			(effects
				(font
					(size 1 1)
					(thickness 0.15)
				)
			)
		)
		(property "Manufacturer" "Murata"
			(at 387.937002 -232.212998 0)
			(layer "F.Fab")
			(hide yes)
			(effects
				(font
					(size 1 1)
					(thickness 0.15)
				)
			)
		)
		(property "Public" "False"
			(at 387.937002 -232.212998 0)
			(layer "F.Fab")
			(hide yes)
			(effects
				(font
					(size 1 1)
					(thickness 0.15)
				)
			)
		)
		(property "Val" "100n"
			(at 387.937002 -232.212998 0)
			(layer "F.Fab")
			(hide yes)
			(effects
				(font
					(size 1 1)
					(thickness 0.15)
				)
			)
		)
		(property "Voltage" "50V"
			(at 387.937002 -232.212998 0)
			(layer "F.Fab")
			(hide yes)
			(effects
				(font
					(size 1 1)
					(thickness 0.15)
				)
			)
		)
		(sheetname "PCIe misc")
		(sheetfile "pcie_misc.kicad_sch")
		(attr smd)
		(fp_rect
			(start -0.925 -0.47)
			(end 0.925 0.47)
			(stroke
				(width 0.05)
				(type default)
			)
			(fill no)
			(layer "F.CrtYd")
		)
		(fp_line
			(start 0.504 -0.25)
			(end 0.504 0.248)
			(stroke
				(width 0.15)
				(type solid)
			)
			(layer "F.Fab")
		)
		(fp_line
			(start -0.494 -0.25)
			(end 0.504 -0.25)
			(stroke
				(width 0.15)
				(type solid)
			)
			(layer "F.Fab")
		)
		(fp_line
			(start 0.504 0.248)
			(end -0.494 0.248)
			(stroke
				(width 0.15)
				(type solid)
			)
			(layer "F.Fab")
		)
		(fp_line
			(start -0.494 0.248)
			(end -0.494 -0.25)
			(stroke
				(width 0.15)
				(type solid)
			)
			(layer "F.Fab")
		)
		(pad "1" smd roundrect
			(at -0.48 0 90)
			(size 0.59 0.64)
			(layers "F.Cu" "F.Mask" "F.Paste")
			(roundrect_rratio 0.25)
			(net 1 "GND")
			(pintype "passive")
			(teardrops
				(best_length_ratio 0.2)
				(max_length 1)
				(best_width_ratio 0.9)
				(max_width 2)
				(curved_edges yes)
				(filter_ratio 0.9)
				(enabled yes)
				(allow_two_segments yes)
				(prefer_zone_connections yes)
			)
		)
		(pad "2" smd roundrect
			(at 0.48 0 90)
			(size 0.59 0.64)
			(layers "F.Cu" "F.Mask" "F.Paste")
			(roundrect_rratio 0.25)
			(net 2 "+3V3")
			(pintype "passive")
			(teardrops
				(best_length_ratio 0.2)
				(max_length 1)
				(best_width_ratio 0.9)
				(max_width 2)
				(curved_edges yes)
				(filter_ratio 0.9)
				(enabled yes)
				(allow_two_segments yes)
				(prefer_zone_connections yes)
			)
		)
	)
	(footprint "antmicro-footprints:C_0402_1005Metric"
		(layer "F.Cu")
		(at 114.35 91.31 90)
		(descr "Capacitor SMD 0402")
		(tags "capacitor SMD 0402")
		(property "Reference" "C9"
			(at 0.85 0.45 90)
			(layer "F.SilkS")
			(effects
				(font
					(size 0.7 0.7)
					(thickness 0.15)
				)
				(justify left bottom)
			)
		)
		(property "Value" "C_1u_0402"
			(at -1.022927 2.155213 90)
			(layer "F.Fab")
			(effects
				(font
					(size 0.7 0.7)
					(thickness 0.15)
				)
				(justify left bottom)
			)
		)
		(property "Datasheet" "https://product.tdk.com/en/search/capacitor/ceramic/mlcc/info?part_no=C1005X6S1A105K050BC"
			(at 0 0 90)
			(layer "F.Fab")
			(hide yes)
			(effects
				(font
					(size 1.27 1.27)
					(thickness 0.15)
				)
			)
		)
		(property "Author" "Antmicro"
			(at 205.66 -23.04 0)
			(layer "F.Fab")
			(hide yes)
			(effects
				(font
					(size 1 1)
					(thickness 0.15)
				)
			)
		)
		(property "Dielectric" ""
			(at 205.66 -23.04 0)
			(layer "F.Fab")
			(hide yes)
			(effects
				(font
					(size 1 1)
					(thickness 0.15)
				)
			)
		)
		(property "License" "Apache-2.0"
			(at 205.66 -23.04 0)
			(layer "F.Fab")
			(hide yes)
			(effects
				(font
					(size 1 1)
					(thickness 0.15)
				)
			)
		)
		(property "MPN" "C1005X6S1A105K050BC"
			(at 205.66 -23.04 0)
			(layer "F.Fab")
			(hide yes)
			(effects
				(font
					(size 1 1)
					(thickness 0.15)
				)
			)
		)
		(property "Manufacturer" "TDK"
			(at 205.66 -23.04 0)
			(layer "F.Fab")
			(hide yes)
			(effects
				(font
					(size 1 1)
					(thickness 0.15)
				)
			)
		)
		(property "Public" "False"
			(at 205.66 -23.04 0)
			(layer "F.Fab")
			(hide yes)
			(effects
				(font
					(size 1 1)
					(thickness 0.15)
				)
			)
		)
		(property "Val" "1u"
			(at 205.66 -23.04 0)
			(layer "F.Fab")
			(hide yes)
			(effects
				(font
					(size 1 1)
					(thickness 0.15)
				)
			)
		)
		(property "Voltage" ""
			(at 205.66 -23.04 0)
			(layer "F.Fab")
			(hide yes)
			(effects
				(font
					(size 1 1)
					(thickness 0.15)
				)
			)
		)
		(sheetname "2xUSB3.0+RJ45")
		(sheetfile "usb3+rj45.kicad_sch")
		(attr smd)
		(fp_rect
			(start -0.925 -0.47)
			(end 0.925 0.47)
			(stroke
				(width 0.05)
				(type default)
			)
			(fill no)
			(layer "F.CrtYd")
		)
		(fp_line
			(start 0.504 -0.25)
			(end 0.504 0.248)
			(stroke
				(width 0.15)
				(type solid)
			)
			(layer "F.Fab")
		)
		(fp_line
			(start -0.494 -0.25)
			(end 0.504 -0.25)
			(stroke
				(width 0.15)
				(type solid)
			)
			(layer "F.Fab")
		)
		(fp_line
			(start 0.504 0.248)
			(end -0.494 0.248)
			(stroke
				(width 0.15)
				(type solid)
			)
			(layer "F.Fab")
		)
		(fp_line
			(start -0.494 0.248)
			(end -0.494 -0.25)
			(stroke
				(width 0.15)
				(type solid)
			)
			(layer "F.Fab")
		)
		(pad "1" smd roundrect
			(at -0.48 0 90)
			(size 0.59 0.64)
			(layers "F.Cu" "F.Mask" "F.Paste")
			(roundrect_rratio 0.25)
			(net 1 "GND")
			(pintype "passive")
			(teardrops
				(best_length_ratio 0.2)
				(max_length 1)
				(best_width_ratio 0.9)
				(max_width 2)
				(curved_edges yes)
				(filter_ratio 0.9)
				(enabled yes)
				(allow_two_segments yes)
				(prefer_zone_connections yes)
			)
		)
		(pad "2" smd roundrect
			(at 0.48 0 90)
			(size 0.59 0.64)
			(layers "F.Cu" "F.Mask" "F.Paste")
			(roundrect_rratio 0.25)
			(net 43 "/2xUSB3.0+RJ45/P2_VBUS")
			(pintype "passive")
			(teardrops
				(best_length_ratio 0.2)
				(max_length 1)
				(best_width_ratio 0.9)
				(max_width 2)
				(curved_edges yes)
				(filter_ratio 0.9)
				(enabled yes)
				(allow_two_segments yes)
				(prefer_zone_connections yes)
			)
		)
	)
	(footprint "antmicro-footprints:R_0402_1005Metric"
		(layer "F.Cu")
		(at 143 134.88 180)
		(descr "Resistor SMD 0402")
		(tags "resistor SMD 0402")
		(property "Reference" "R270"
			(at 0.75 -0.43 0)
			(layer "F.SilkS")
			(effects
				(font
					(size 0.7 0.7)
					(thickness 0.15)
				)
				(justify right bottom)
			)
		)
		(property "Value" "R_10k_0402"
			(at -1.011843 1.772047 0)
			(layer "F.Fab")
			(effects
				(font
					(size 0.7 0.7)
					(thickness 0.15)
				)
				(justify right bottom)
			)
		)
		(property "Datasheet" "https://www.bourns.com/docs/product-datasheets/cr.pdf"
			(at 0 0 180)
			(layer "F.Fab")
			(hide yes)
			(effects
				(font
					(size 1.27 1.27)
					(thickness 0.15)
				)
			)
		)
		(property "Author" "Antmicro"
			(at 286 269.76 0)
			(layer "F.Fab")
			(hide yes)
			(effects
				(font
					(size 1 1)
					(thickness 0.15)
				)
			)
		)
		(property "License" "Apache-2.0"
			(at 286 269.76 0)
			(layer "F.Fab")
			(hide yes)
			(effects
				(font
					(size 1 1)
					(thickness 0.15)
				)
			)
		)
		(property "MPN" "CR0402-FX-1002GLF"
			(at 286 269.76 0)
			(layer "F.Fab")
			(hide yes)
			(effects
				(font
					(size 1 1)
					(thickness 0.15)
				)
			)
		)
		(property "Manufacturer" "Bourns"
			(at 286 269.76 0)
			(layer "F.Fab")
			(hide yes)
			(effects
				(font
					(size 1 1)
					(thickness 0.15)
				)
			)
		)
		(property "Public" "False"
			(at 286 269.76 0)
			(layer "F.Fab")
			(hide yes)
			(effects
				(font
					(size 1 1)
					(thickness 0.15)
				)
			)
		)
		(property "Tolerance" "1%"
			(at 286 269.76 0)
			(layer "F.Fab")
			(hide yes)
			(effects
				(font
					(size 1 1)
					(thickness 0.15)
				)
			)
		)
		(property "Val" "10k"
			(at 286 269.76 0)
			(layer "F.Fab")
			(hide yes)
			(effects
				(font
					(size 1 1)
					(thickness 0.15)
				)
			)
		)
		(sheetname "KR to SFI #1")
		(sheetfile "kr_sfi.kicad_sch")
		(attr smd dnp)
		(fp_rect
			(start -0.925 -0.47)
			(end 0.925 0.47)
			(stroke
				(width 0.05)
				(type default)
			)
			(fill no)
			(layer "F.CrtYd")
		)
		(fp_rect
			(start -0.5 -0.25)
			(end 0.5 0.25)
			(stroke
				(width 0.15)
				(type solid)
			)
			(fill no)
			(layer "F.Fab")
		)
		(pad "1" smd roundrect
			(at -0.48 0 180)
			(size 0.59 0.64)
			(layers "F.Cu" "F.Mask" "F.Paste")
			(roundrect_rratio 0.25)
			(net 663 "Net-(U43C-ST)")
			(pintype "passive")
			(teardrops
				(best_length_ratio 0.2)
				(max_length 1)
				(best_width_ratio 0.9)
				(max_width 2)
				(curved_edges yes)
				(filter_ratio 0.9)
				(enabled yes)
				(allow_two_segments yes)
				(prefer_zone_connections yes)
			)
		)
		(pad "2" smd roundrect
			(at 0.48 0 180)
			(size 0.59 0.64)
			(layers "F.Cu" "F.Mask" "F.Paste")
			(roundrect_rratio 0.25)
			(net 78 "+1V8")
			(pintype "passive")
			(teardrops
				(best_length_ratio 0.2)
				(max_length 1)
				(best_width_ratio 0.9)
				(max_width 2)
				(curved_edges yes)
				(filter_ratio 0.9)
				(enabled yes)
				(allow_two_segments yes)
				(prefer_zone_connections yes)
			)
		)
	)
	(footprint "antmicro-footprints:C_0402_1005Metric"
		(layer "F.Cu")
		(at 109.757 76.776 90)
		(descr "Capacitor SMD 0402")
		(tags "capacitor SMD 0402")
		(property "Reference" "C31"
			(at -1.034 -0.507 90)
			(layer "F.SilkS")
			(effects
				(font
					(size 0.7 0.7)
					(thickness 0.15)
				)
				(justify left bottom)
			)
		)
		(property "Value" "C_47p_0402"
			(at -1.022927 2.155213 90)
			(layer "F.Fab")
			(effects
				(font
					(size 0.7 0.7)
					(thickness 0.15)
				)
				(justify left bottom)
			)
		)
		(property "Datasheet" "https://www.kemet.com/en/us/capacitors/product/C0402C470J5GACTU.html"
			(at 0 0 90)
			(layer "F.Fab")
			(hide yes)
			(effects
				(font
					(size 1.27 1.27)
					(thickness 0.15)
				)
			)
		)
		(property "Author" "Antmicro"
			(at 186.533 -32.981 0)
			(layer "F.Fab")
			(hide yes)
			(effects
				(font
					(size 1 1)
					(thickness 0.15)
				)
			)
		)
		(property "Dielectric" "C0G"
			(at 186.533 -32.981 0)
			(layer "F.Fab")
			(hide yes)
			(effects
				(font
					(size 1 1)
					(thickness 0.15)
				)
			)
		)
		(property "License" "Apache-2.0"
			(at 186.533 -32.981 0)
			(layer "F.Fab")
			(hide yes)
			(effects
				(font
					(size 1 1)
					(thickness 0.15)
				)
			)
		)
		(property "MPN" "C0402C470J5GACTU"
			(at 186.533 -32.981 0)
			(layer "F.Fab")
			(hide yes)
			(effects
				(font
					(size 1 1)
					(thickness 0.15)
				)
			)
		)
		(property "Manufacturer" "KEMET"
			(at 186.533 -32.981 0)
			(layer "F.Fab")
			(hide yes)
			(effects
				(font
					(size 1 1)
					(thickness 0.15)
				)
			)
		)
		(property "Public" "False"
			(at 186.533 -32.981 0)
			(layer "F.Fab")
			(hide yes)
			(effects
				(font
					(size 1 1)
					(thickness 0.15)
				)
			)
		)
		(property "Val" "47p"
			(at 186.533 -32.981 0)
			(layer "F.Fab")
			(hide yes)
			(effects
				(font
					(size 1 1)
					(thickness 0.15)
				)
			)
		)
		(property "Voltage" ""
			(at 186.533 -32.981 0)
			(layer "F.Fab")
			(hide yes)
			(effects
				(font
					(size 1 1)
					(thickness 0.15)
				)
			)
		)
		(sheetname "USB-C console")
		(sheetfile "usb-c_console.kicad_sch")
		(attr smd)
		(fp_rect
			(start -0.925 -0.47)
			(end 0.925 0.47)
			(stroke
				(width 0.05)
				(type default)
			)
			(fill no)
			(layer "F.CrtYd")
		)
		(fp_line
			(start 0.504 -0.25)
			(end 0.504 0.248)
			(stroke
				(width 0.15)
				(type solid)
			)
			(layer "F.Fab")
		)
		(fp_line
			(start -0.494 -0.25)
			(end 0.504 -0.25)
			(stroke
				(width 0.15)
				(type solid)
			)
			(layer "F.Fab")
		)
		(fp_line
			(start 0.504 0.248)
			(end -0.494 0.248)
			(stroke
				(width 0.15)
				(type solid)
			)
			(layer "F.Fab")
		)
		(fp_line
			(start -0.494 0.248)
			(end -0.494 -0.25)
			(stroke
				(width 0.15)
				(type solid)
			)
			(layer "F.Fab")
		)
		(pad "1" smd roundrect
			(at -0.48 0 90)
			(size 0.59 0.64)
			(layers "F.Cu" "F.Mask" "F.Paste")
			(roundrect_rratio 0.25)
			(net 1 "GND")
			(pintype "passive")
			(teardrops
				(best_length_ratio 0.2)
				(max_length 1)
				(best_width_ratio 0.9)
				(max_width 2)
				(curved_edges yes)
				(filter_ratio 0.9)
				(enabled yes)
				(allow_two_segments yes)
				(prefer_zone_connections yes)
			)
		)
		(pad "2" smd roundrect
			(at 0.48 0 90)
			(size 0.59 0.64)
			(layers "F.Cu" "F.Mask" "F.Paste")
			(roundrect_rratio 0.25)
			(net 56 "/USB-C console/USB_D-")
			(pintype "passive")
			(teardrops
				(best_length_ratio 0.2)
				(max_length 1)
				(best_width_ratio 0.9)
				(max_width 2)
				(curved_edges yes)
				(filter_ratio 0.9)
				(enabled yes)
				(allow_two_segments yes)
				(prefer_zone_connections yes)
			)
		)
	)
)
